(kicad_pcb
	(version 20260206)
	(generator "pcbnew")
	(generator_version "10.0")
	(general
		(thickness 1.6)
		(legacy_teardrops no)
	)
	(paper "A4")
	(title_block
		(title "9054_F0T_PDB_BD_GPU_F_V04_1213_1550_OCP.brd")
		(comment 1 "Grand Teton / footprints 463-468 of 608")
	)
	(layers
		(0 "F.Cu" signal "TOP")
		(4 "In1.Cu" signal "GND")
		(6 "In2.Cu" signal "IN1")
		(8 "In3.Cu" signal "GND1")
		(10 "In4.Cu" signal "VCC")
		(12 "In5.Cu" signal "VCC1")
		(14 "In6.Cu" signal "GND2")
		(16 "In7.Cu" signal "IN2")
		(18 "In8.Cu" signal "GND3")
		(2 "B.Cu" signal "BOTTOM")
		(9 "F.Adhes" user "F.Adhesive")
		(11 "B.Adhes" user "B.Adhesive")
		(13 "F.Paste" user "Package Geometry/Pastemask Top")
		(15 "B.Paste" user "Package Geometry/Pastemask Bottom")
		(5 "F.SilkS" user "Ref Des/Silkscreen Top")
		(7 "B.SilkS" user "Ref Des/Silkscreen Bottom")
		(1 "F.Mask" user "Board Geometry/Soldermask Top")
		(3 "B.Mask" user "Board Geometry/Soldermask Bottom")
		(17 "Dwgs.User" user "User.Drawings")
		(19 "Cmts.User" user "User.Comments")
		(21 "Eco1.User" user "User.Eco1")
		(23 "Eco2.User" user "User.Eco2")
		(25 "Edge.Cuts" user "Board Geometry/Outline")
		(27 "Margin" user)
		(31 "F.CrtYd" user "Package Geometry/Place Bound Top")
		(29 "B.CrtYd" user "Package Geometry/Place Bound Bottom")
		(35 "F.Fab" user "Ref Des/Assembly Top")
		(33 "B.Fab" user "Ref Des/Assembly Bottom")
	)
	(footprint ""
		(layer "B.Cu")
		(at 163.3474 -78.359 180)
		(property "Reference" "PR7011"
			(at 0 0 0)
			(layer "B.SilkS")
			(hide yes)
			(effects
				(font
					(size 1.27 1.27)
				)
				(justify mirror)
			)
		)
		(property "Value" ""
			(at 0 0 0)
			(layer "B.Fab")
			(effects
				(font
					(size 1.27 1.27)
				)
				(justify mirror)
			)
		)
		(duplicate_pad_numbers_are_jumpers no)
		(fp_line
			(start 0.7874 0.4064)
			(end 0.7874 -0.4064)
			(stroke
				(width 0.1524)
				(type default)
			)
			(layer "B.SilkS")
		)
		(fp_line
			(start 0.7874 -0.4064)
			(end -0.7874 -0.4064)
			(stroke
				(width 0.1524)
				(type default)
			)
			(layer "B.SilkS")
		)
		(fp_line
			(start -0.7874 0.4064)
			(end 0.7874 0.4064)
			(stroke
				(width 0.1524)
				(type default)
			)
			(layer "B.SilkS")
		)
		(fp_line
			(start -0.7874 -0.4064)
			(end -0.7874 0.4064)
			(stroke
				(width 0.1524)
				(type default)
			)
			(layer "B.SilkS")
		)
		(fp_line
			(start 0.67945 0.3048)
			(end 0.67945 -0.305054)
			(stroke
				(width 0.1)
				(type default)
			)
			(layer "B.Fab")
		)
		(fp_line
			(start 0.67945 -0.305054)
			(end 0.12065 -0.305054)
			(stroke
				(width 0.1)
				(type default)
			)
			(layer "B.Fab")
		)
		(fp_line
			(start 0.12065 0.3048)
			(end 0.67945 0.3048)
			(stroke
				(width 0.1)
				(type default)
			)
			(layer "B.Fab")
		)
		(fp_line
			(start 0.12065 0.2794)
			(end 0.12065 0.3048)
			(stroke
				(width 0.1)
				(type default)
			)
			(layer "B.Fab")
		)
		(fp_line
			(start 0.12065 -0.2794)
			(end -0.12065 -0.2794)
			(stroke
				(width 0.1)
				(type default)
			)
			(layer "B.Fab")
		)
		(fp_line
			(start 0.12065 -0.305054)
			(end 0.12065 -0.2794)
			(stroke
				(width 0.1)
				(type default)
			)
			(layer "B.Fab")
		)
		(fp_line
			(start -0.120396 0.3048)
			(end -0.120396 0.2794)
			(stroke
				(width 0.1)
				(type default)
			)
			(layer "B.Fab")
		)
		(fp_line
			(start -0.120396 0.2794)
			(end 0.12065 0.2794)
			(stroke
				(width 0.1)
				(type default)
			)
			(layer "B.Fab")
		)
		(fp_line
			(start -0.12065 -0.2794)
			(end -0.12065 -0.3048)
			(stroke
				(width 0.1)
				(type default)
			)
			(layer "B.Fab")
		)
		(fp_line
			(start -0.12065 -0.3048)
			(end -0.67945 -0.3048)
			(stroke
				(width 0.1)
				(type default)
			)
			(layer "B.Fab")
		)
		(fp_line
			(start -0.67945 0.3048)
			(end -0.120396 0.3048)
			(stroke
				(width 0.1)
				(type default)
			)
			(layer "B.Fab")
		)
		(fp_line
			(start -0.67945 -0.3048)
			(end -0.67945 0.3048)
			(stroke
				(width 0.1)
				(type default)
			)
			(layer "B.Fab")
		)
		(pad "1" smd circle
			(at 0.40005 0)
			(size 0 0)
			(layers "B.Cu" "B.Mask" "B.Paste")
			(net "HS2_TMR2")
		)
		(pad "2" smd circle
			(at -0.40005 0)
			(size 0 0)
			(layers "B.Cu" "B.Mask" "B.Paste")
			(net "GND1_FIELD_SIGNAL")
		)
	)
	(footprint ""
		(layer "B.Cu")
		(at 274.4724 -84.201 90)
		(property "Reference" "PR480"
			(at 0 0 90)
			(layer "B.SilkS")
			(hide yes)
			(effects
				(font
					(size 1.27 1.27)
				)
				(justify mirror)
			)
		)
		(property "Value" ""
			(at 0 0 90)
			(layer "B.Fab")
			(effects
				(font
					(size 1.27 1.27)
				)
				(justify mirror)
			)
		)
		(duplicate_pad_numbers_are_jumpers no)
		(fp_line
			(start 1.651 -0.8382)
			(end -1.651 -0.8382)
			(stroke
				(width 0.1524)
				(type default)
			)
			(layer "B.SilkS")
		)
		(fp_line
			(start -1.651 -0.8382)
			(end -1.651 0.8382)
			(stroke
				(width 0.1524)
				(type default)
			)
			(layer "B.SilkS")
		)
		(fp_line
			(start 1.651 0.8382)
			(end 1.651 -0.8382)
			(stroke
				(width 0.1524)
				(type default)
			)
			(layer "B.SilkS")
		)
		(fp_line
			(start -1.651 0.8382)
			(end 1.651 0.8382)
			(stroke
				(width 0.1524)
				(type default)
			)
			(layer "B.SilkS")
		)
		(fp_line
			(start 1.559814 -0.7366)
			(end 1.559814 0.7366)
			(stroke
				(width 0.1)
				(type default)
			)
			(layer "B.Fab")
		)
		(fp_line
			(start 1.524 -0.7366)
			(end 1.559814 -0.7366)
			(stroke
				(width 0.1)
				(type default)
			)
			(layer "B.Fab")
		)
		(fp_line
			(start -1.524 -0.7366)
			(end 1.524 -0.7366)
			(stroke
				(width 0.1)
				(type default)
			)
			(layer "B.Fab")
		)
		(fp_line
			(start -1.560576 -0.7366)
			(end -1.524 -0.7366)
			(stroke
				(width 0.1)
				(type default)
			)
			(layer "B.Fab")
		)
		(fp_line
			(start 1.559814 0.7366)
			(end 1.524 0.7366)
			(stroke
				(width 0.1)
				(type default)
			)
			(layer "B.Fab")
		)
		(fp_line
			(start 1.524 0.7366)
			(end -1.524 0.7366)
			(stroke
				(width 0.1)
				(type default)
			)
			(layer "B.Fab")
		)
		(fp_line
			(start -1.524 0.7366)
			(end -1.560576 0.7366)
			(stroke
				(width 0.1)
				(type default)
			)
			(layer "B.Fab")
		)
		(fp_line
			(start -1.560576 0.7366)
			(end -1.560576 -0.7366)
			(stroke
				(width 0.1)
				(type default)
			)
			(layer "B.Fab")
		)
		(pad "1" smd rect
			(at 0.94996 0 90)
			(size 1.1176 1.3716)
			(layers "B.Cu" "B.Mask" "B.Paste")
			(net "P52V_1")
		)
		(pad "2" smd rect
			(at -0.94996 0 90)
			(size 1.1176 1.3716)
			(layers "B.Cu" "B.Mask" "B.Paste")
			(net "P52V_HS1_OV")
		)
	)
	(footprint ""
		(layer "B.Cu")
		(at 286.2834 -69.342 -90)
		(property "Reference" "PR27"
			(at 0 0 90)
			(layer "B.SilkS")
			(hide yes)
			(effects
				(font
					(size 1.27 1.27)
				)
				(justify mirror)
			)
		)
		(property "Value" ""
			(at 0 0 90)
			(layer "B.Fab")
			(effects
				(font
					(size 1.27 1.27)
				)
				(justify mirror)
			)
		)
		(duplicate_pad_numbers_are_jumpers no)
		(fp_line
			(start -0.7874 0.4064)
			(end 0.7874 0.4064)
			(stroke
				(width 0.1524)
				(type default)
			)
			(layer "B.SilkS")
		)
		(fp_line
			(start 0.7874 0.4064)
			(end 0.7874 -0.4064)
			(stroke
				(width 0.1524)
				(type default)
			)
			(layer "B.SilkS")
		)
		(fp_line
			(start -0.7874 -0.4064)
			(end -0.7874 0.4064)
			(stroke
				(width 0.1524)
				(type default)
			)
			(layer "B.SilkS")
		)
		(fp_line
			(start 0.7874 -0.4064)
			(end -0.7874 -0.4064)
			(stroke
				(width 0.1524)
				(type default)
			)
			(layer "B.SilkS")
		)
		(fp_line
			(start -0.67945 0.3048)
			(end -0.120396 0.3048)
			(stroke
				(width 0.1)
				(type default)
			)
			(layer "B.Fab")
		)
		(fp_line
			(start -0.120396 0.3048)
			(end -0.120396 0.2794)
			(stroke
				(width 0.1)
				(type default)
			)
			(layer "B.Fab")
		)
		(fp_line
			(start 0.12065 0.3048)
			(end 0.67945 0.3048)
			(stroke
				(width 0.1)
				(type default)
			)
			(layer "B.Fab")
		)
		(fp_line
			(start 0.67945 0.3048)
			(end 0.67945 -0.305054)
			(stroke
				(width 0.1)
				(type default)
			)
			(layer "B.Fab")
		)
		(fp_line
			(start -0.120396 0.2794)
			(end 0.12065 0.2794)
			(stroke
				(width 0.1)
				(type default)
			)
			(layer "B.Fab")
		)
		(fp_line
			(start 0.12065 0.2794)
			(end 0.12065 0.3048)
			(stroke
				(width 0.1)
				(type default)
			)
			(layer "B.Fab")
		)
		(fp_line
			(start -0.12065 -0.2794)
			(end -0.12065 -0.3048)
			(stroke
				(width 0.1)
				(type default)
			)
			(layer "B.Fab")
		)
		(fp_line
			(start 0.12065 -0.2794)
			(end -0.12065 -0.2794)
			(stroke
				(width 0.1)
				(type default)
			)
			(layer "B.Fab")
		)
		(fp_line
			(start -0.67945 -0.3048)
			(end -0.67945 0.3048)
			(stroke
				(width 0.1)
				(type default)
			)
			(layer "B.Fab")
		)
		(fp_line
			(start -0.12065 -0.3048)
			(end -0.67945 -0.3048)
			(stroke
				(width 0.1)
				(type default)
			)
			(layer "B.Fab")
		)
		(fp_line
			(start 0.12065 -0.305054)
			(end 0.12065 -0.2794)
			(stroke
				(width 0.1)
				(type default)
			)
			(layer "B.Fab")
		)
		(fp_line
			(start 0.67945 -0.305054)
			(end 0.12065 -0.305054)
			(stroke
				(width 0.1)
				(type default)
			)
			(layer "B.Fab")
		)
		(pad "1" smd circle
			(at 0.40005 0 90)
			(size 0 0)
			(layers "B.Cu" "B.Mask" "B.Paste")
			(net "P52V_HS1_INTVCC")
		)
		(pad "2" smd circle
			(at -0.40005 0 90)
			(size 0 0)
			(layers "B.Cu" "B.Mask" "B.Paste")
			(net "P52V_HS1_SCK")
		)
	)
	(footprint ""
		(layer "B.Cu")
		(at 161.717736 -72.263 180)
		(property "Reference" "PR7007"
			(at 0 0 0)
			(layer "B.SilkS")
			(hide yes)
			(effects
				(font
					(size 1.27 1.27)
				)
				(justify mirror)
			)
		)
		(property "Value" ""
			(at 0 0 0)
			(layer "B.Fab")
			(effects
				(font
					(size 1.27 1.27)
				)
				(justify mirror)
			)
		)
		(duplicate_pad_numbers_are_jumpers no)
		(fp_line
			(start 0.7874 0.4064)
			(end 0.7874 -0.4064)
			(stroke
				(width 0.1524)
				(type default)
			)
			(layer "B.SilkS")
		)
		(fp_line
			(start 0.7874 -0.4064)
			(end -0.7874 -0.4064)
			(stroke
				(width 0.1524)
				(type default)
			)
			(layer "B.SilkS")
		)
		(fp_line
			(start -0.7874 0.4064)
			(end 0.7874 0.4064)
			(stroke
				(width 0.1524)
				(type default)
			)
			(layer "B.SilkS")
		)
		(fp_line
			(start -0.7874 -0.4064)
			(end -0.7874 0.4064)
			(stroke
				(width 0.1524)
				(type default)
			)
			(layer "B.SilkS")
		)
		(fp_line
			(start 0.67945 0.3048)
			(end 0.67945 -0.305054)
			(stroke
				(width 0.1)
				(type default)
			)
			(layer "B.Fab")
		)
		(fp_line
			(start 0.67945 -0.305054)
			(end 0.12065 -0.305054)
			(stroke
				(width 0.1)
				(type default)
			)
			(layer "B.Fab")
		)
		(fp_line
			(start 0.12065 0.3048)
			(end 0.67945 0.3048)
			(stroke
				(width 0.1)
				(type default)
			)
			(layer "B.Fab")
		)
		(fp_line
			(start 0.12065 0.2794)
			(end 0.12065 0.3048)
			(stroke
				(width 0.1)
				(type default)
			)
			(layer "B.Fab")
		)
		(fp_line
			(start 0.12065 -0.2794)
			(end -0.12065 -0.2794)
			(stroke
				(width 0.1)
				(type default)
			)
			(layer "B.Fab")
		)
		(fp_line
			(start 0.12065 -0.305054)
			(end 0.12065 -0.2794)
			(stroke
				(width 0.1)
				(type default)
			)
			(layer "B.Fab")
		)
		(fp_line
			(start -0.120396 0.3048)
			(end -0.120396 0.2794)
			(stroke
				(width 0.1)
				(type default)
			)
			(layer "B.Fab")
		)
		(fp_line
			(start -0.120396 0.2794)
			(end 0.12065 0.2794)
			(stroke
				(width 0.1)
				(type default)
			)
			(layer "B.Fab")
		)
		(fp_line
			(start -0.12065 -0.2794)
			(end -0.12065 -0.3048)
			(stroke
				(width 0.1)
				(type default)
			)
			(layer "B.Fab")
		)
		(fp_line
			(start -0.12065 -0.3048)
			(end -0.67945 -0.3048)
			(stroke
				(width 0.1)
				(type default)
			)
			(layer "B.Fab")
		)
		(fp_line
			(start -0.67945 0.3048)
			(end -0.120396 0.3048)
			(stroke
				(width 0.1)
				(type default)
			)
			(layer "B.Fab")
		)
		(fp_line
			(start -0.67945 -0.3048)
			(end -0.67945 0.3048)
			(stroke
				(width 0.1)
				(type default)
			)
			(layer "B.Fab")
		)
		(pad "1" smd circle
			(at 0.40005 0)
			(size 0 0)
			(layers "B.Cu" "B.Mask" "B.Paste")
			(net "P52V_HS2_SIO")
		)
		(pad "2" smd circle
			(at -0.40005 0)
			(size 0 0)
			(layers "B.Cu" "B.Mask" "B.Paste")
			(net "GND1_FIELD_SIGNAL")
		)
	)
	(footprint ""
		(layer "B.Cu")
		(at 291.9984 -60.833 90)
		(property "Reference" "R158"
			(at 0 0 90)
			(layer "B.SilkS")
			(hide yes)
			(effects
				(font
					(size 1.27 1.27)
				)
				(justify mirror)
			)
		)
		(property "Value" ""
			(at 0 0 90)
			(layer "B.Fab")
			(effects
				(font
					(size 1.27 1.27)
				)
				(justify mirror)
			)
		)
		(duplicate_pad_numbers_are_jumpers no)
		(fp_line
			(start 0.7874 -0.4064)
			(end -0.7874 -0.4064)
			(stroke
				(width 0.1524)
				(type default)
			)
			(layer "B.SilkS")
		)
		(fp_line
			(start -0.7874 -0.4064)
			(end -0.7874 0.4064)
			(stroke
				(width 0.1524)
				(type default)
			)
			(layer "B.SilkS")
		)
		(fp_line
			(start 0.7874 0.4064)
			(end 0.7874 -0.4064)
			(stroke
				(width 0.1524)
				(type default)
			)
			(layer "B.SilkS")
		)
		(fp_line
			(start -0.7874 0.4064)
			(end 0.7874 0.4064)
			(stroke
				(width 0.1524)
				(type default)
			)
			(layer "B.SilkS")
		)
		(fp_line
			(start 0.67945 -0.305054)
			(end 0.12065 -0.305054)
			(stroke
				(width 0.1)
				(type default)
			)
			(layer "B.Fab")
		)
		(fp_line
			(start 0.12065 -0.305054)
			(end 0.12065 -0.2794)
			(stroke
				(width 0.1)
				(type default)
			)
			(layer "B.Fab")
		)
		(fp_line
			(start -0.12065 -0.3048)
			(end -0.67945 -0.3048)
			(stroke
				(width 0.1)
				(type default)
			)
			(layer "B.Fab")
		)
		(fp_line
			(start -0.67945 -0.3048)
			(end -0.67945 0.3048)
			(stroke
				(width 0.1)
				(type default)
			)
			(layer "B.Fab")
		)
		(fp_line
			(start 0.12065 -0.2794)
			(end -0.12065 -0.2794)
			(stroke
				(width 0.1)
				(type default)
			)
			(layer "B.Fab")
		)
		(fp_line
			(start -0.12065 -0.2794)
			(end -0.12065 -0.3048)
			(stroke
				(width 0.1)
				(type default)
			)
			(layer "B.Fab")
		)
		(fp_line
			(start 0.12065 0.2794)
			(end 0.12065 0.3048)
			(stroke
				(width 0.1)
				(type default)
			)
			(layer "B.Fab")
		)
		(fp_line
			(start -0.120396 0.2794)
			(end 0.12065 0.2794)
			(stroke
				(width 0.1)
				(type default)
			)
			(layer "B.Fab")
		)
		(fp_line
			(start 0.67945 0.3048)
			(end 0.67945 -0.305054)
			(stroke
				(width 0.1)
				(type default)
			)
			(layer "B.Fab")
		)
		(fp_line
			(start 0.12065 0.3048)
			(end 0.67945 0.3048)
			(stroke
				(width 0.1)
				(type default)
			)
			(layer "B.Fab")
		)
		(fp_line
			(start -0.120396 0.3048)
			(end -0.120396 0.2794)
			(stroke
				(width 0.1)
				(type default)
			)
			(layer "B.Fab")
		)
		(fp_line
			(start -0.67945 0.3048)
			(end -0.120396 0.3048)
			(stroke
				(width 0.1)
				(type default)
			)
			(layer "B.Fab")
		)
		(pad "1" smd circle
			(at 0.40005 0 270)
			(size 0 0)
			(layers "B.Cu" "B.Mask" "B.Paste")
			(net "P52V_HS1_ADR0")
		)
		(pad "2" smd circle
			(at -0.40005 0 270)
			(size 0 0)
			(layers "B.Cu" "B.Mask" "B.Paste")
			(net "GND_FIELD_SIGNAL")
		)
	)
	(footprint ""
		(layer "B.Cu")
		(at 162.733736 -70.485 180)
		(property "Reference" "PR7015"
			(at 0 0 0)
			(layer "B.SilkS")
			(hide yes)
			(effects
				(font
					(size 1.27 1.27)
				)
				(justify mirror)
			)
		)
		(property "Value" ""
			(at 0 0 0)
			(layer "B.Fab")
			(effects
				(font
					(size 1.27 1.27)
				)
				(justify mirror)
			)
		)
		(duplicate_pad_numbers_are_jumpers no)
		(fp_line
			(start 0.7874 0.4064)
			(end 0.7874 -0.4064)
			(stroke
				(width 0.1524)
				(type default)
			)
			(layer "B.SilkS")
		)
		(fp_line
			(start 0.7874 -0.4064)
			(end -0.7874 -0.4064)
			(stroke
				(width 0.1524)
				(type default)
			)
			(layer "B.SilkS")
		)
		(fp_line
			(start -0.7874 0.4064)
			(end 0.7874 0.4064)
			(stroke
				(width 0.1524)
				(type default)
			)
			(layer "B.SilkS")
		)
		(fp_line
			(start -0.7874 -0.4064)
			(end -0.7874 0.4064)
			(stroke
				(width 0.1524)
				(type default)
			)
			(layer "B.SilkS")
		)
		(fp_line
			(start 0.67945 0.3048)
			(end 0.67945 -0.305054)
			(stroke
				(width 0.1)
				(type default)
			)
			(layer "B.Fab")
		)
		(fp_line
			(start 0.67945 -0.305054)
			(end 0.12065 -0.305054)
			(stroke
				(width 0.1)
				(type default)
			)
			(layer "B.Fab")
		)
		(fp_line
			(start 0.12065 0.3048)
			(end 0.67945 0.3048)
			(stroke
				(width 0.1)
				(type default)
			)
			(layer "B.Fab")
		)
		(fp_line
			(start 0.12065 0.2794)
			(end 0.12065 0.3048)
			(stroke
				(width 0.1)
				(type default)
			)
			(layer "B.Fab")
		)
		(fp_line
			(start 0.12065 -0.2794)
			(end -0.12065 -0.2794)
			(stroke
				(width 0.1)
				(type default)
			)
			(layer "B.Fab")
		)
		(fp_line
			(start 0.12065 -0.305054)
			(end 0.12065 -0.2794)
			(stroke
				(width 0.1)
				(type default)
			)
			(layer "B.Fab")
		)
		(fp_line
			(start -0.120396 0.3048)
			(end -0.120396 0.2794)
			(stroke
				(width 0.1)
				(type default)
			)
			(layer "B.Fab")
		)
		(fp_line
			(start -0.120396 0.2794)
			(end 0.12065 0.2794)
			(stroke
				(width 0.1)
				(type default)
			)
			(layer "B.Fab")
		)
		(fp_line
			(start -0.12065 -0.2794)
			(end -0.12065 -0.3048)
			(stroke
				(width 0.1)
				(type default)
			)
			(layer "B.Fab")
		)
		(fp_line
			(start -0.12065 -0.3048)
			(end -0.67945 -0.3048)
			(stroke
				(width 0.1)
				(type default)
			)
			(layer "B.Fab")
		)
		(fp_line
			(start -0.67945 0.3048)
			(end -0.120396 0.3048)
			(stroke
				(width 0.1)
				(type default)
			)
			(layer "B.Fab")
		)
		(fp_line
			(start -0.67945 -0.3048)
			(end -0.67945 0.3048)
			(stroke
				(width 0.1)
				(type default)
			)
			(layer "B.Fab")
		)
		(pad "1" smd circle
			(at 0.40005 0)
			(size 0 0)
			(layers "B.Cu" "B.Mask" "B.Paste")
			(net "P52V_HS2_SCK")
		)
		(pad "2" smd circle
			(at -0.40005 0)
			(size 0 0)
			(layers "B.Cu" "B.Mask" "B.Paste")
			(net "GND1_FIELD_SIGNAL")
		)
	)
)
